(kicad_pcb
	(version 20260206)
	(generator "pcbnew")
	(generator_version "10.0")
	(general
		(thickness 1.6)
		(legacy_teardrops no)
	)
	(paper "A4")
	(title_block
		(title "Bryce Canyon_R.DPB_16317-1_OCP.brd")
		(comment 1 "Bryce Canyon / footprints 2018-2022 of 2099")
	)
	(layers
		(0 "F.Cu" signal "TOP")
		(4 "In1.Cu" signal "L2GND")
		(6 "In2.Cu" signal "L3")
		(8 "In3.Cu" signal "L4VCC")
		(10 "In4.Cu" signal "L5VCC")
		(12 "In5.Cu" signal "L6")
		(14 "In6.Cu" signal "L7GND")
		(2 "B.Cu" signal "BOTTOM")
		(9 "F.Adhes" user "F.Adhesive")
		(11 "B.Adhes" user "B.Adhesive")
		(13 "F.Paste" user "Package Geometry/Pastemask Top")
		(15 "B.Paste" user "Package Geometry/Pastemask Bottom")
		(5 "F.SilkS" user "Ref Des/Silkscreen Top")
		(7 "B.SilkS" user "Ref Des/Silkscreen Bottom")
		(1 "F.Mask" user "Board Geometry/Soldermask Top")
		(3 "B.Mask" user "Board Geometry/Soldermask Bottom")
		(17 "Dwgs.User" user "User.Drawings")
		(19 "Cmts.User" user "User.Comments")
		(21 "Eco1.User" user "User.Eco1")
		(23 "Eco2.User" user "User.Eco2")
		(25 "Edge.Cuts" user "Board Geometry/Outline")
		(27 "Margin" user)
		(31 "F.CrtYd" user "Package Geometry/Place Bound Top")
		(29 "B.CrtYd" user "Package Geometry/Place Bound Bottom")
		(35 "F.Fab" user "Ref Des/Assembly Top")
		(33 "B.Fab" user "Ref Des/Assembly Bottom")
	)
	(footprint ""
		(layer "B.Cu")
		(at 438.301384 -114.600228 -90)
		(property "Reference" "U34"
			(at 0 0 90)
			(layer "B.SilkS")
			(hide yes)
			(effects
				(font
					(size 1.27 1.27)
				)
				(justify mirror)
			)
		)
		(property "Value" "TPS53319DQPR-GP"
			(at -4.7498 -5.6896 270)
			(unlocked yes)
			(layer "B.Fab")
			(hide yes)
			(effects
				(font
					(size 1.016 1.016)
					(thickness 0.1524)
				)
				(justify mirror)
			)
		)
		(property "Device Type" "QFN22G6050-G6133H60"
			(at -4.7498 -7.2136 270)
			(unlocked yes)
			(layer "B.Fab")
			(hide yes)
			(effects
				(font
					(size 1.016 1.016)
					(thickness 0.1524)
				)
				(justify mirror)
			)
		)
		(duplicate_pad_numbers_are_jumpers no)
		(fp_line
			(start -3.556 3.5179)
			(end -3.556 2.2479)
			(stroke
				(width 0.1524)
				(type default)
			)
			(layer "B.SilkS")
		)
		(fp_line
			(start -2.286 3.5179)
			(end -3.556 3.5179)
			(stroke
				(width 0.1524)
				(type default)
			)
			(layer "B.SilkS")
		)
		(fp_line
			(start 3.556 3.5179)
			(end 2.286 3.5179)
			(stroke
				(width 0.1524)
				(type default)
			)
			(layer "B.SilkS")
		)
		(fp_line
			(start -1.500124 3.262122)
			(end -1.500124 4.024122)
			(stroke
				(width 0.1524)
				(type default)
			)
			(layer "B.SilkS")
		)
		(fp_line
			(start 0.999998 3.262122)
			(end 0.999998 3.770122)
			(stroke
				(width 0.1524)
				(type default)
			)
			(layer "B.SilkS")
		)
		(fp_line
			(start 3.556 2.2479)
			(end 3.556 3.5179)
			(stroke
				(width 0.1524)
				(type default)
			)
			(layer "B.SilkS")
		)
		(fp_line
			(start -0.500126 -3.262122)
			(end -0.500126 -3.770122)
			(stroke
				(width 0.1524)
				(type default)
			)
			(layer "B.SilkS")
		)
		(fp_line
			(start 1.999996 -3.262122)
			(end 1.999996 -4.024122)
			(stroke
				(width 0.1524)
				(type default)
			)
			(layer "B.SilkS")
		)
		(fp_line
			(start 2.286 -3.5179)
			(end 3.556 -3.5179)
			(stroke
				(width 0.1524)
				(type default)
			)
			(layer "B.SilkS")
		)
		(fp_line
			(start 3.556 -3.5179)
			(end 3.556 -2.2479)
			(stroke
				(width 0.1524)
				(type default)
			)
			(layer "B.SilkS")
		)
		(fp_poly
			(pts
				(xy -3.556 -3.5179) (xy -2.5273 -3.5179) (xy -3.556 -2.4892)
			)
			(stroke
				(width 0)
				(type default)
			)
			(fill yes)
			(layer "B.SilkS")
		)
		(fp_rect
			(start 2.9972 2.5019)
			(end -2.9972 -2.5019)
			(stroke
				(width 0)
				(type default)
			)
			(fill no)
			(layer "B.CrtYd")
		)
		(fp_poly
			(pts
				(xy -3.556 -2.5019) (xy 2.9972 -2.5019) (xy 2.9972 2.5019) (xy -2.9972 2.5019) (xy -2.9972 -2.4892)
				(xy -3.556 -2.4892) (xy -3.556 3.5179) (xy 3.556 3.5179) (xy 3.556 -3.5179) (xy -3.556 -3.5179)
			)
			(stroke
				(width 0)
				(type default)
			)
			(fill no)
			(layer "B.CrtYd")
		)
		(fp_rect
			(start 3.556 3.5179)
			(end -3.556 -3.5179)
			(stroke
				(width 0)
				(type default)
			)
			(fill no)
			(layer "B.Fab")
		)
		(pad "1" smd rect
			(at -2.500122 -2.449322 90)
			(size 0.3048 1.1176)
			(layers "B.Cu" "B.Mask" "B.Paste")
			(net "P5V_B_4_VFB")
		)
		(pad "2" smd rect
			(at -1.999996 -2.449322 90)
			(size 0.3048 1.1176)
			(layers "B.Cu" "B.Mask" "B.Paste")
			(net "P5V_B_4_EN_R")
		)
		(pad "3" smd rect
			(at -1.500124 -2.449322 90)
			(size 0.3048 1.1176)
			(layers "B.Cu" "B.Mask" "B.Paste")
			(net "P5V_B_4_PGOOD")
		)
		(pad "4" smd rect
			(at -0.999998 -2.449322 90)
			(size 0.3048 1.1176)
			(layers "B.Cu" "B.Mask" "B.Paste")
			(net "P5V_B_4_VBST")
		)
		(pad "5" smd rect
			(at -0.500126 -2.449322 90)
			(size 0.3048 1.1176)
			(layers "B.Cu" "B.Mask" "B.Paste")
			(net "P5V_B_4_ROVP")
		)
		(pad "6" smd rect
			(at 0 -2.449322 90)
			(size 0.3048 1.1176)
			(layers "B.Cu" "B.Mask" "B.Paste")
			(net "P5V_B_4_LL")
		)
		(pad "7" smd rect
			(at 0.500126 -2.449322 90)
			(size 0.3048 1.1176)
			(layers "B.Cu" "B.Mask" "B.Paste")
			(net "P5V_B_4_LL")
		)
		(pad "8" smd rect
			(at 0.999998 -2.449322 90)
			(size 0.3048 1.1176)
			(layers "B.Cu" "B.Mask" "B.Paste")
			(net "P5V_B_4_LL")
		)
		(pad "9" smd rect
			(at 1.500124 -2.449322 90)
			(size 0.3048 1.1176)
			(layers "B.Cu" "B.Mask" "B.Paste")
			(net "P5V_B_4_LL")
		)
		(pad "10" smd rect
			(at 1.999996 -2.449322 90)
			(size 0.3048 1.1176)
			(layers "B.Cu" "B.Mask" "B.Paste")
			(net "P5V_B_4_LL")
		)
		(pad "11" smd rect
			(at 2.500122 -2.449322 90)
			(size 0.3048 1.1176)
			(layers "B.Cu" "B.Mask" "B.Paste")
			(net "P5V_B_4_LL")
		)
		(pad "12" smd rect
			(at 2.500122 2.449322 90)
			(size 0.3048 1.1176)
			(layers "B.Cu" "B.Mask" "B.Paste")
			(net "P12V_B_4_VIN_U34")
		)
		(pad "13" smd rect
			(at 1.999996 2.449322 90)
			(size 0.3048 1.1176)
			(layers "B.Cu" "B.Mask" "B.Paste")
			(net "P12V_B_4_VIN_U34")
		)
		(pad "14" smd rect
			(at 1.500124 2.449322 90)
			(size 0.3048 1.1176)
			(layers "B.Cu" "B.Mask" "B.Paste")
			(net "P12V_B_4_VIN_U34")
		)
		(pad "15" smd rect
			(at 0.999998 2.449322 90)
			(size 0.3048 1.1176)
			(layers "B.Cu" "B.Mask" "B.Paste")
			(net "P12V_B_4_VIN_U34")
		)
		(pad "16" smd rect
			(at 0.500126 2.449322 90)
			(size 0.3048 1.1176)
			(layers "B.Cu" "B.Mask" "B.Paste")
			(net "P12V_B_4_VIN_U34")
		)
		(pad "17" smd rect
			(at 0 2.449322 90)
			(size 0.3048 1.1176)
			(layers "B.Cu" "B.Mask" "B.Paste")
			(net "P12V_B_4_VIN_U34")
		)
		(pad "18" smd rect
			(at -0.500126 2.449322 90)
			(size 0.3048 1.1176)
			(layers "B.Cu" "B.Mask" "B.Paste")
			(net "P5V_B_4_VREG")
		)
		(pad "19" smd rect
			(at -0.999998 2.449322 90)
			(size 0.3048 1.1176)
			(layers "B.Cu" "B.Mask" "B.Paste")
			(net "P12V_B_4_VDD_U34")
		)
		(pad "20" smd rect
			(at -1.500124 2.449322 90)
			(size 0.3048 1.1176)
			(layers "B.Cu" "B.Mask" "B.Paste")
			(net "P5V_B_4_MODE")
		)
		(pad "21" smd rect
			(at -1.999996 2.449322 90)
			(size 0.3048 1.1176)
			(layers "B.Cu" "B.Mask" "B.Paste")
			(net "P5V_B_4_TRIP")
		)
		(pad "22" smd rect
			(at -2.500122 2.449322 90)
			(size 0.3048 1.1176)
			(layers "B.Cu" "B.Mask" "B.Paste")
			(net "P5V_B_4_RF")
		)
		(pad "23" smd custom
			(at 0 0 90)
			(size 0.83185 0.83185)
			(layers "B.Cu" "B.Mask" "B.Paste")
			(net "GND")
			(options
				(clearance outline)
				(anchor circle)
			)
			(primitives
				(gr_poly
					(pts
						(xy -2.7813 -1.6637) (xy -2.7813 -1.2954) (xy -3.048 -1.2954) (xy -3.048 -0.9525) (xy -2.7813 -0.9525)
						(xy -2.7813 0.9525) (xy -3.048 0.9525) (xy -3.048 1.2954) (xy -2.7813 1.2954) (xy -2.7813 1.6637)
						(xy 2.7813 1.6637) (xy 2.7813 1.2954) (xy 3.048 1.2954) (xy 3.048 0.9525) (xy 2.7813 0.9525) (xy 2.7813 -0.9525)
						(xy 3.048 -0.9525) (xy 3.048 -1.2954) (xy 2.7813 -1.2954) (xy 2.7813 -1.6637)
					)
					(width 0)
					(fill yes)
				)
			)
		)
	)
	(footprint ""
		(layer "B.Cu")
		(at 48.707802 -228.35235 180)
		(property "Reference" "C633"
			(at 0 0 0)
			(layer "B.SilkS")
			(hide yes)
			(effects
				(font
					(size 1.27 1.27)
				)
				(justify mirror)
			)
		)
		(property "Value" "SC10U16V5KX-7-GP-U"
			(at 0.0762 -6.1214 180)
			(unlocked yes)
			(layer "B.Fab")
			(hide yes)
			(effects
				(font
					(size 1.016 1.016)
					(thickness 0.1524)
				)
				(justify mirror)
			)
		)
		(property "Device Type" "C805H58"
			(at 0.0762 -8.1534 180)
			(unlocked yes)
			(layer "B.Fab")
			(hide yes)
			(effects
				(font
					(size 1.016 1.016)
					(thickness 0.1524)
				)
				(justify mirror)
			)
		)
		(duplicate_pad_numbers_are_jumpers no)
		(fp_line
			(start -0.635 0)
			(end 0.635 0)
			(stroke
				(width 0.508)
				(type default)
			)
			(layer "B.SilkS")
		)
		(fp_rect
			(start 0.9652 1.778)
			(end -0.9652 -1.778)
			(stroke
				(width 0)
				(type default)
			)
			(fill no)
			(layer "B.CrtYd")
		)
		(fp_poly
			(pts
				(xy 0.9652 -1.778) (xy -0.9652 -1.778) (xy -0.9652 1.778) (xy 0.9652 1.778)
			)
			(stroke
				(width 0)
				(type default)
			)
			(fill no)
			(layer "B.Fab")
		)
		(pad "1" smd rect
			(at 0 -0.9652)
			(size 1.397 1.143)
			(layers "B.Cu" "B.Mask" "B.Paste")
			(net "P5V_B_1")
		)
		(pad "2" smd rect
			(at 0 0.9652)
			(size 1.397 1.143)
			(layers "B.Cu" "B.Mask" "B.Paste")
			(net "GND")
		)
	)
	(footprint ""
		(layer "B.Cu")
		(at 258.22783 -280.680668)
		(property "Reference" "C695"
			(at 0 0 0)
			(layer "B.SilkS")
			(hide yes)
			(effects
				(font
					(size 1.27 1.27)
				)
				(justify mirror)
			)
		)
		(property "Value" "SC3300P50V2KX-1GP"
			(at -1.1811 -2.7051 0)
			(unlocked yes)
			(layer "B.Fab")
			(hide yes)
			(effects
				(font
					(size 1.016 1.016)
					(thickness 0.1524)
				)
				(justify mirror)
			)
		)
		(property "Device Type" "C402H22"
			(at -1.1811 -4.2291 0)
			(unlocked yes)
			(layer "B.Fab")
			(hide yes)
			(effects
				(font
					(size 1.016 1.016)
					(thickness 0.1524)
				)
				(justify mirror)
			)
		)
		(duplicate_pad_numbers_are_jumpers no)
		(fp_rect
			(start 0.4318 0.9525)
			(end -0.4318 -0.9525)
			(stroke
				(width 0)
				(type default)
			)
			(fill no)
			(layer "B.CrtYd")
		)
		(fp_rect
			(start 0.4318 0.9525)
			(end -0.4318 -0.9525)
			(stroke
				(width 0)
				(type default)
			)
			(fill no)
			(layer "B.Fab")
		)
		(pad "1" smd custom
			(at 0 -0.4445 180)
			(size 0.1524 0.1524)
			(layers "B.Cu" "B.Mask" "B.Paste")
			(net "P3V3_STBY_SS")
			(options
				(clearance outline)
				(anchor circle)
			)
			(primitives
				(gr_poly
					(pts
						(arc
							(start 0.3048 0.2032)
							(mid 0.275042 0.275042)
							(end 0.2032 0.3048)
						)
						(arc
							(start -0.2032 0.3048)
							(mid -0.275042 0.275042)
							(end -0.3048 0.2032)
						)
						(arc
							(start -0.3048 -0.2032)
							(mid -0.275042 -0.275042)
							(end -0.2032 -0.3048)
						)
						(arc
							(start 0.2032 -0.3048)
							(mid 0.275042 -0.275042)
							(end 0.3048 -0.2032)
						)
					)
					(width 0)
					(fill yes)
				)
			)
		)
		(pad "2" smd custom
			(at 0 0.4445 180)
			(size 0.1524 0.1524)
			(layers "B.Cu" "B.Mask" "B.Paste")
			(net "AGND_P3V3_STBY")
			(options
				(clearance outline)
				(anchor circle)
			)
			(primitives
				(gr_poly
					(pts
						(arc
							(start 0.3048 0.2032)
							(mid 0.275042 0.275042)
							(end 0.2032 0.3048)
						)
						(arc
							(start -0.2032 0.3048)
							(mid -0.275042 0.275042)
							(end -0.3048 0.2032)
						)
						(arc
							(start -0.3048 -0.2032)
							(mid -0.275042 -0.275042)
							(end -0.2032 -0.3048)
						)
						(arc
							(start 0.2032 -0.3048)
							(mid 0.275042 -0.275042)
							(end 0.3048 -0.2032)
						)
					)
					(width 0)
					(fill yes)
				)
			)
		)
	)
	(footprint ""
		(layer "B.Cu")
		(at 432.145186 -116.765578 -90)
		(property "Reference" "C678"
			(at 0 0 90)
			(layer "B.SilkS")
			(hide yes)
			(effects
				(font
					(size 1.27 1.27)
				)
				(justify mirror)
			)
		)
		(property "Value" "SC4D7U25V5KX-1-GP"
			(at 0.0762 -6.1214 270)
			(unlocked yes)
			(layer "B.Fab")
			(hide yes)
			(effects
				(font
					(size 1.016 1.016)
					(thickness 0.1524)
				)
				(justify mirror)
			)
		)
		(property "Device Type" "C805H58"
			(at 0.0762 -8.1534 270)
			(unlocked yes)
			(layer "B.Fab")
			(hide yes)
			(effects
				(font
					(size 1.016 1.016)
					(thickness 0.1524)
				)
				(justify mirror)
			)
		)
		(duplicate_pad_numbers_are_jumpers no)
		(fp_line
			(start -0.635 0)
			(end 0.635 0)
			(stroke
				(width 0.508)
				(type default)
			)
			(layer "B.SilkS")
		)
		(fp_rect
			(start 0.9652 1.778)
			(end -0.9652 -1.778)
			(stroke
				(width 0)
				(type default)
			)
			(fill no)
			(layer "B.CrtYd")
		)
		(fp_poly
			(pts
				(xy 0.9652 -1.778) (xy -0.9652 -1.778) (xy -0.9652 1.778) (xy 0.9652 1.778)
			)
			(stroke
				(width 0)
				(type default)
			)
			(fill no)
			(layer "B.Fab")
		)
		(pad "1" smd rect
			(at 0 -0.9652 90)
			(size 1.397 1.143)
			(layers "B.Cu" "B.Mask" "B.Paste")
			(net "P12V_B_4_VDD_U34")
		)
		(pad "2" smd rect
			(at 0 0.9652 90)
			(size 1.397 1.143)
			(layers "B.Cu" "B.Mask" "B.Paste")
			(net "GND")
		)
	)
	(footprint ""
		(layer "B.Cu")
		(at 259.865622 -284.124654 -90)
		(property "Reference" "R1175"
			(at 0 0 90)
			(layer "B.SilkS")
			(hide yes)
			(effects
				(font
					(size 1.27 1.27)
				)
				(justify mirror)
			)
		)
		(property "Value" "10KR2F-2-GP"
			(at -0.064008 -3.993896 270)
			(unlocked yes)
			(layer "B.Fab")
			(hide yes)
			(effects
				(font
					(size 1.016 1.016)
					(thickness 0.1524)
				)
				(justify mirror)
			)
		)
		(property "Device Type" "R402H16"
			(at -0.064008 -5.517896 270)
			(unlocked yes)
			(layer "B.Fab")
			(hide yes)
			(effects
				(font
					(size 1.016 1.016)
					(thickness 0.1524)
				)
				(justify mirror)
			)
		)
		(duplicate_pad_numbers_are_jumpers no)
		(fp_line
			(start -0.508 -0.9398)
			(end 0.508 -0.9398)
			(stroke
				(width 0.1524)
				(type default)
			)
			(layer "B.SilkS")
		)
		(fp_line
			(start 0.508 -0.9398)
			(end 0.508 0.9398)
			(stroke
				(width 0.1524)
				(type default)
			)
			(layer "B.SilkS")
		)
		(fp_rect
			(start 0.508 0.9398)
			(end -0.508 -0.9398)
			(stroke
				(width 0)
				(type default)
			)
			(fill no)
			(layer "B.CrtYd")
		)
		(fp_rect
			(start 0.508 0.9398)
			(end -0.508 -0.9398)
			(stroke
				(width 0)
				(type default)
			)
			(fill no)
			(layer "B.Fab")
		)
		(pad "1" smd custom
			(at 0 -0.4445 90)
			(size 0.1397 0.1397)
			(layers "B.Cu" "B.Mask" "B.Paste")
			(net "AGND_P3V3_STBY")
			(options
				(clearance outline)
				(anchor circle)
			)
			(primitives
				(gr_poly
					(pts
						(arc
							(start -0.1778 0.2794)
							(mid -0.249642 0.249642)
							(end -0.2794 0.1778)
						)
						(arc
							(start -0.2794 -0.1778)
							(mid -0.249642 -0.249642)
							(end -0.1778 -0.2794)
						)
						(arc
							(start 0.1778 -0.2794)
							(mid 0.249642 -0.249642)
							(end 0.2794 -0.1778)
						)
						(arc
							(start 0.2794 0.1778)
							(mid 0.249642 0.249642)
							(end 0.1778 0.2794)
						)
					)
					(width 0)
					(fill yes)
				)
			)
		)
		(pad "2" smd custom
			(at 0 0.4445 90)
			(size 0.1397 0.1397)
			(layers "B.Cu" "B.Mask" "B.Paste")
			(net "P3V3_STBY_VFB")
			(options
				(clearance outline)
				(anchor circle)
			)
			(primitives
				(gr_poly
					(pts
						(arc
							(start -0.1778 0.2794)
							(mid -0.249642 0.249642)
							(end -0.2794 0.1778)
						)
						(arc
							(start -0.2794 -0.1778)
							(mid -0.249642 -0.249642)
							(end -0.1778 -0.2794)
						)
						(arc
							(start 0.1778 -0.2794)
							(mid 0.249642 -0.249642)
							(end 0.2794 -0.1778)
						)
						(arc
							(start 0.2794 0.1778)
							(mid 0.249642 0.249642)
							(end 0.1778 0.2794)
						)
					)
					(width 0)
					(fill yes)
				)
			)
		)
	)
)
